# BASEBOARD_FAB2 (Tioga Pass) — schematic netlist excerpt (pin names and nets, part order shuffled) for the footprints in the layout excerpt that follows; sources: Cadence DE-HDL packaged netlist, KiCad conversion of Wiwynn_Tioga_Pass_MB.brd

C6P16  CAP_A  22.0UF 4V 20% X6S  pkg 0603V  page 202 : A = PVCCIN_CPU0 ; B = GND
R4P23  RES  150.0 1% CHIP  pkg 0402  page 112 : A = PVCCIO_CPU0 ; B = XDP_CPU0_TDO
C1M22  CAP_A  0.1UF 16V 10% X7R  pkg 0402V  page 186 : A = P12V_STBY ; B = GND

(kicad_pcb
	(version 20260206)
	(generator "pcbnew")
	(generator_version "10.0")
	(general
		(thickness 1.6)
		(legacy_teardrops no)
	)
	(paper "A4")
	(title_block
		(title "Wiwynn_Tioga_Pass_MB.brd")
		(comment 1 "Tioga Pass / footprints 4028-4030 of 4770")
	)
	(layers
		(0 "F.Cu" signal "TOP")
		(4 "In1.Cu" signal "L2GND")
		(6 "In2.Cu" signal "L3")
		(8 "In3.Cu" signal "L4GND")
		(10 "In4.Cu" signal "L5")
		(12 "In5.Cu" signal "L6GND")
		(14 "In6.Cu" signal "L7VCC")
		(16 "In7.Cu" signal "L8VCC")
		(18 "In8.Cu" signal "L9GND")
		(20 "In9.Cu" signal "L10")
		(22 "In10.Cu" signal "L11GND")
		(24 "In11.Cu" signal "L12")
		(26 "In12.Cu" signal "L13GND")
		(2 "B.Cu" signal "BOTTOM")
		(9 "F.Adhes" user "F.Adhesive")
		(11 "B.Adhes" user "B.Adhesive")
		(13 "F.Paste" user "Package Geometry/Pastemask Top")
		(15 "B.Paste" user "Package Geometry/Pastemask Bottom")
		(5 "F.SilkS" user "Ref Des/Silkscreen Top")
		(7 "B.SilkS" user "Ref Des/Silkscreen Bottom")
		(1 "F.Mask" user "Board Geometry/Soldermask Top")
		(3 "B.Mask" user "Board Geometry/Soldermask Bottom")
		(17 "Dwgs.User" user "User.Drawings")
		(19 "Cmts.User" user "User.Comments")
		(21 "Eco1.User" user "User.Eco1")
		(23 "Eco2.User" user "User.Eco2")
		(25 "Edge.Cuts" user "Board Geometry/Outline")
		(27 "Margin" user)
		(31 "F.CrtYd" user "Package Geometry/Place Bound Top")
		(29 "B.CrtYd" user "Package Geometry/Place Bound Bottom")
		(35 "F.Fab" user "Ref Des/Assembly Top")
		(33 "B.Fab" user "Ref Des/Assembly Bottom")
	)
	(footprint ""
		(layer "B.Cu")
		(at 295.1226 -65.462404 90)
		(property "Reference" "R4P23"
			(at 0 0 90)
			(layer "B.SilkS")
			(hide yes)
			(effects
				(font
					(size 1.27 1.27)
				)
				(justify mirror)
			)
		)
		(property "Value" ""
			(at 0 0 90)
			(layer "B.Fab")
			(effects
				(font
					(size 1.27 1.27)
				)
				(justify mirror)
			)
		)
		(duplicate_pad_numbers_are_jumpers no)
		(fp_poly
			(pts
				(xy 0.2794 -0.1016) (xy -0.2794 -0.1016) (xy -0.2794 0.9906) (xy 0.2794 0.9906)
			)
			(stroke
				(width 0)
				(type default)
			)
			(fill no)
			(layer "B.CrtYd")
		)
		(fp_line
			(start 0.2794 -0.1016)
			(end 0.2794 0.9906)
			(stroke
				(width 0.1)
				(type default)
			)
			(layer "B.Fab")
		)
		(fp_line
			(start -0.2794 -0.1016)
			(end 0.2794 -0.1016)
			(stroke
				(width 0.1)
				(type default)
			)
			(layer "B.Fab")
		)
		(fp_line
			(start 0.2794 0.9906)
			(end -0.2794 0.9906)
			(stroke
				(width 0.1)
				(type default)
			)
			(layer "B.Fab")
		)
		(fp_line
			(start -0.2794 0.9906)
			(end -0.2794 -0.1016)
			(stroke
				(width 0.1)
				(type default)
			)
			(layer "B.Fab")
		)
		(pad "1" smd rect
			(at 0 0 270)
			(size 0.508 0.508)
			(layers "B.Cu" "B.Mask" "B.Paste")
			(net "PVCCIO_CPU0")
		)
		(pad "2" smd rect
			(at 0 0.889 270)
			(size 0.508 0.508)
			(layers "B.Cu" "B.Mask" "B.Paste")
			(net "XDP_CPU0_TDO")
		)
		(zone
			(layer "B.Cu")
			(hatch none 0.5)
			(connect_pads
				(clearance 0)
			)
			(min_thickness 0.25)
			(keepout
				(tracks allowed)
				(vias not_allowed)
				(pads allowed)
				(copperpour not_allowed)
				(footprints allowed)
			)
			(placement
				(enabled no)
				(sheetname "")
			)
			(fill
				(thermal_gap 0.5)
				(thermal_bridge_width 0.5)
				(island_removal_mode 0)
			)
			(polygon
				(pts
					(xy 295.3766 -65.716404) (xy 295.3766 -65.208404) (xy 295.7576 -65.208404) (xy 295.7576 -65.716404)
				)
			)
		)
		(zone
			(layer "B.Cu")
			(hatch none 0.5)
			(connect_pads
				(clearance 0)
			)
			(min_thickness 0.25)
			(keepout
				(tracks not_allowed)
				(vias allowed)
				(pads allowed)
				(copperpour not_allowed)
				(footprints allowed)
			)
			(placement
				(enabled no)
				(sheetname "")
			)
			(fill
				(thermal_gap 0.5)
				(thermal_bridge_width 0.5)
				(island_removal_mode 0)
			)
			(polygon
				(pts
					(xy 295.7576 -65.716404) (xy 295.7576 -65.208404) (xy 295.3766 -65.208404) (xy 295.3766 -65.716404)
				)
			)
		)
	)
	(footprint ""
		(layer "B.Cu")
		(at 488.442 -113.2332 90)
		(property "Reference" "C1M22"
			(at 0 0 90)
			(layer "B.SilkS")
			(hide yes)
			(effects
				(font
					(size 1.27 1.27)
				)
				(justify mirror)
			)
		)
		(property "Value" ""
			(at 0 0 90)
			(layer "B.Fab")
			(effects
				(font
					(size 1.27 1.27)
				)
				(justify mirror)
			)
		)
		(duplicate_pad_numbers_are_jumpers no)
		(fp_rect
			(start -0.3048 -0.1016)
			(end 0.3048 0.9906)
			(stroke
				(width 0)
				(type default)
			)
			(fill no)
			(layer "B.CrtYd")
		)
		(fp_line
			(start 0.3048 -0.1016)
			(end 0.3048 0.9906)
			(stroke
				(width 0.1)
				(type default)
			)
			(layer "B.Fab")
		)
		(fp_line
			(start -0.3048 -0.1016)
			(end 0.3048 -0.1016)
			(stroke
				(width 0.1)
				(type default)
			)
			(layer "B.Fab")
		)
		(fp_line
			(start 0.3048 0.9906)
			(end -0.3048 0.9906)
			(stroke
				(width 0.1)
				(type default)
			)
			(layer "B.Fab")
		)
		(fp_line
			(start -0.3048 0.9906)
			(end -0.3048 -0.1016)
			(stroke
				(width 0.1)
				(type default)
			)
			(layer "B.Fab")
		)
		(pad "1" smd rect
			(at 0 0 270)
			(size 0.508 0.508)
			(layers "B.Cu" "B.Mask" "B.Paste")
			(net "P12V_STBY")
		)
		(pad "2" smd rect
			(at 0 0.889 270)
			(size 0.508 0.508)
			(layers "B.Cu" "B.Mask" "B.Paste")
			(net "GND")
		)
		(zone
			(layer "B.Cu")
			(hatch none 0.5)
			(connect_pads
				(clearance 0)
			)
			(min_thickness 0.25)
			(keepout
				(tracks allowed)
				(vias not_allowed)
				(pads allowed)
				(copperpour not_allowed)
				(footprints allowed)
			)
			(placement
				(enabled no)
				(sheetname "")
			)
			(fill
				(thermal_gap 0.5)
				(thermal_bridge_width 0.5)
				(island_removal_mode 0)
			)
			(polygon
				(pts
					(xy 488.696 -112.9792) (xy 489.077 -112.9792) (xy 489.077 -113.4872) (xy 488.696 -113.4872)
				)
			)
		)
		(zone
			(layer "B.Cu")
			(hatch none 0.5)
			(connect_pads
				(clearance 0)
			)
			(min_thickness 0.25)
			(keepout
				(tracks not_allowed)
				(vias allowed)
				(pads allowed)
				(copperpour not_allowed)
				(footprints allowed)
			)
			(placement
				(enabled no)
				(sheetname "")
			)
			(fill
				(thermal_gap 0.5)
				(thermal_bridge_width 0.5)
				(island_removal_mode 0)
			)
			(polygon
				(pts
					(xy 488.696 -112.9792) (xy 489.077 -112.9792) (xy 489.077 -113.4872) (xy 488.696 -113.4872)
				)
			)
		)
	)
	(footprint ""
		(layer "B.Cu")
		(at 214.503 -78.4098)
		(property "Reference" "C6P16"
			(at 0 0 0)
			(layer "B.SilkS")
			(hide yes)
			(effects
				(font
					(size 1.27 1.27)
				)
				(justify mirror)
			)
		)
		(property "Value" ""
			(at 0 0 0)
			(layer "B.Fab")
			(effects
				(font
					(size 1.27 1.27)
				)
				(justify mirror)
			)
		)
		(duplicate_pad_numbers_are_jumpers no)
		(fp_poly
			(pts
				(xy 0.4953 -0.2032) (xy -0.4953 -0.2032) (xy -0.4953 1.6002) (xy 0.4953 1.6002)
			)
			(stroke
				(width 0)
				(type default)
			)
			(fill no)
			(layer "B.CrtYd")
		)
		(fp_line
			(start -0.4953 -0.2032)
			(end -0.4953 1.6002)
			(stroke
				(width 0.1)
				(type default)
			)
			(layer "B.Fab")
		)
		(fp_line
			(start -0.4953 1.6002)
			(end 0.4953 1.6002)
			(stroke
				(width 0.1)
				(type default)
			)
			(layer "B.Fab")
		)
		(fp_line
			(start 0.4953 -0.2032)
			(end -0.4953 -0.2032)
			(stroke
				(width 0.1)
				(type default)
			)
			(layer "B.Fab")
		)
		(fp_line
			(start 0.4953 1.6002)
			(end 0.4953 -0.2032)
			(stroke
				(width 0.1)
				(type default)
			)
			(layer "B.Fab")
		)
		(pad "1" smd rect
			(at 0 0 180)
			(size 0.762 0.889)
			(layers "B.Cu" "B.Mask" "B.Paste")
			(net "PVCCIN_CPU0")
		)
		(pad "2" smd rect
			(at 0 1.397 180)
			(size 0.762 0.889)
			(layers "B.Cu" "B.Mask" "B.Paste")
			(net "GND")
		)
		(zone
			(layer "B.Cu")
			(hatch none 0.5)
			(connect_pads
				(clearance 0)
			)
			(min_thickness 0.25)
			(keepout
				(tracks not_allowed)
				(vias allowed)
				(pads allowed)
				(copperpour not_allowed)
				(footprints allowed)
			)
			(placement
				(enabled no)
				(sheetname "")
			)
			(fill
				(thermal_gap 0.5)
				(thermal_bridge_width 0.5)
				(island_removal_mode 0)
			)
			(polygon
				(pts
					(xy 214.884 -77.9653) (xy 214.122 -77.9653) (xy 214.122 -77.4573) (xy 214.884 -77.4573)
				)
			)
		)
	)
)
